# T6G (Grand Teton) — schematic netlist excerpt (pin names and nets, part order shuffled) for the footprints in the layout excerpt that follows; sources: Cadence DE-HDL packaged netlist, KiCad conversion of 04192023_DAF0TMB3IC0_F0TG_MB_C_brd_V02_OCP.brd

J68  SCONN288_DDR506112002KQ  IO  pkg DDR288S_1-1VXC  page 95
  VIN_BULK0  = P12V_MEM_CPU0
  RFU0  = NC
  VIN_MGMT  = P3V3_AUX
  HSCL  = I3C_SPD_DDRJ_CPU0_SCL
  HSDA  = I3C_SPD_DDRJ_CPU0_SDA
  VSS0  = GND
  DQ0_A  = M_J_CPU0_SA_DQ<0>
  VSS1  = GND
  DQ1_A  = M_J_CPU0_SA_DQ<1>
  VSS2  = GND
  DQS0_A_T  = M_J_CPU0_SA_DQS_DP<0>
  DQS0_A_C  = M_J_CPU0_SA_DQS_DN<0>
  VSS3  = GND
  DQ4_A  = M_J_CPU0_SA_DQ<4>
  VSS4  = GND
  DQ5_A  = M_J_CPU0_SA_DQ<5>
  VSS5  = GND
  DQ8_A  = M_J_CPU0_SA_DQ<8>
  VSS6  = GND
  DQ9_A  = M_J_CPU0_SA_DQ<9>
  VSS7  = GND
  DQS1_A_T  = M_J_CPU0_SA_DQS_DP<1>
  DQS1_A_C  = M_J_CPU0_SA_DQS_DN<1>
  VSS8  = GND
  DQ12_A  = M_J_CPU0_SA_DQ<12>
  VSS9  = GND
  DQ13_A  = M_J_CPU0_SA_DQ<13>
  VSS10  = GND
  DQ16_A  = M_J_CPU0_SA_DQ<16>
  VSS11  = GND
  DQ17_A  = M_J_CPU0_SA_DQ<17>
  VSS12  = GND
  DQS2_A_T  = M_J_CPU0_SA_DQS_DP<2>
  DQS2_A_C  = M_J_CPU0_SA_DQS_DN<2>
  VSS13  = GND
  DQ20_A  = M_J_CPU0_SA_DQ<20>
  VSS14  = GND
  DQ21_A  = M_J_CPU0_SA_DQ<21>
  VSS15  = GND
  DQ24_A  = M_J_CPU0_SA_DQ<24>
  VSS16  = GND
  DQ25_A  = M_J_CPU0_SA_DQ<25>
  VSS17  = GND
  DQS3_A_T  = M_J_CPU0_SA_DQS_DP<3>
  DQS3_A_C  = M_J_CPU0_SA_DQS_DN<3>
  VSS18  = GND
  DQ28_A  = M_J_CPU0_SA_DQ<28>
  VSS19  = GND
  DQ29_A  = M_J_CPU0_SA_DQ<29>
  VSS20  = GND
  CB0_A  = M_J_CPU0_SA_CB<0>
  VSS21  = GND
  CB1_A  = M_J_CPU0_SA_CB<1>
  VSS22  = GND
  DQS4_A_T  = M_J_CPU0_SA_DQS_DP<4>
  DQS4_A_C  = M_J_CPU0_SA_DQS_DN<4>
  VSS23  = GND
  CB4_A  = M_J_CPU0_SA_CB<4>
  VSS24  = GND
  CB5_A  = M_J_CPU0_SA_CB<5>
  VSS25  = GND
  ALERT_N  = M_J_CPU0_ALERT_N
  VSS26  = GND
  CS0_A_N  = M_J_CPU0_SA_CS_N<0>
  VSS27  = GND
  CA0_A  = M_J_CPU0_SA_CA<0>
  VSS28  = GND
  CA2_A  = M_J_CPU0_SA_CA<2>
  VSS29  = GND
  CA4_A  = M_J_CPU0_SA_CA<4>
  VSS30  = GND
  CA6_A  = M_J_CPU0_SA_CA<6>
  VSS31  = GND
  PAR_A  = M_J_CPU0_SA_PAR
  VSS32  = GND
  CA0_B  = M_J_CPU0_SB_CA<0>
  VSS33  = GND
  CA2_B  = M_J_CPU0_SB_CA<2>
  VSS34  = GND
  CA4_B  = M_J_CPU0_SB_CA<4>
  VSS35  = GND
  CA6_B  = M_J_CPU0_SB_CA<6>
  VSS36  = GND
  CS0_B_N  = M_J_CPU0_SB_CS_N<0>
  VSS37  = GND
  \lbd||rsp_a_n\  = M_J_CPU0_SA_RSP<0>
  \lbs||rsp_b_n\  = M_J_CPU0_SB_RSP<0>
  VSS38  = GND
  CB4_B  = M_J_CPU0_SB_CB<4>
  VSS39  = GND
  CB5_B  = M_J_CPU0_SB_CB<5>
  VSS40  = GND
  \dqs9_b_t||tdqs9_b_t||dbi4_b_n\  = M_J_CPU0_SB_DQS_DP<9>
  \dqs9_b_c||tdqs9_b_c\  = M_J_CPU0_SB_DQS_DN<9>
  VSS41  = GND
  CB0_B  = M_J_CPU0_SB_CB<0>
  VSS42  = GND
  CB1_B  = M_J_CPU0_SB_CB<1>
  VSS43  = GND
  DQ0_B  = M_J_CPU0_SB_DQ<0>
  VSS44  = GND
  DQ1_B  = M_J_CPU0_SB_DQ<1>
  VSS45  = GND
  DQS0_B_T  = M_J_CPU0_SB_DQS_DP<0>
  DQS0_B_C  = M_J_CPU0_SB_DQS_DN<0>
  VSS46  = GND
  DQ4_B  = M_J_CPU0_SB_DQ<4>
  VSS47  = GND
  DQ5_B  = M_J_CPU0_SB_DQ<5>
  VSS48  = GND
  DQ8_B  = M_J_CPU0_SB_DQ<8>
  VSS49  = GND
  DQ9_B  = M_J_CPU0_SB_DQ<9>
  VSS50  = GND
  DQS1_B_T  = M_J_CPU0_SB_DQS_DP<1>
  DQS1_B_C  = M_J_CPU0_SB_DQS_DN<1>
  VSS51  = GND
  DQ12_B  = M_J_CPU0_SB_DQ<12>
  VSS52  = GND
  DQ13_B  = M_J_CPU0_SB_DQ<13>
  VSS53  = GND
  DQ16_B  = M_J_CPU0_SB_DQ<16>
  VSS54  = GND
  DQ17_B  = M_J_CPU0_SB_DQ<17>
  VSS55  = GND
  DQS2_B_T  = M_J_CPU0_SB_DQS_DP<2>
  DQS2_B_C  = M_J_CPU0_SB_DQS_DN<2>
  VSS56  = GND
  DQ20_B  = M_J_CPU0_SB_DQ<20>
  VSS57  = GND
  DQ21_B  = M_J_CPU0_SB_DQ<21>
  VSS58  = GND
  DQ24_B  = M_J_CPU0_SB_DQ<24>
  VSS59  = GND
  DQ25_B  = M_J_CPU0_SB_DQ<25>
  VSS60  = GND
  DQS3_B_T  = M_J_CPU0_SB_DQS_DP<3>
  DQS3_B_C  = M_J_CPU0_SB_DQS_DN<3>
  VSS61  = GND
  DQ28_B  = M_J_CPU0_SB_DQ<28>
  VSS62  = GND
  DQ29_B  = M_J_CPU0_SB_DQ<29>
  VSS63  = GND
  RFU1  = NC
  VIN_BULK1  = P12V_MEM_CPU0
  VIN_BULK2  = P12V_MEM_CPU0
  \pwr_good||fail_n\  = PWRGD_CHJ_CPU0_DIMM
  HAS  = PD_CHJ_CPU0_DIMM_SAA
  RFU2  = NC
  RFU3  = NC
  VSS64  = GND
  DQ2_A  = M_J_CPU0_SA_DQ<2>
  VSS65  = GND
  DQ3_A  = M_J_CPU0_SA_DQ<3>
  VSS66  = GND
  \dqs5_a_c||tdqs5_a_c||dqs5_a_t||tdqs5_a_t\  = M_J_CPU0_SA_DQS_DN<5>
  \dqs5_a_t||tdqs5_a_t\  = M_J_CPU0_SA_DQS_DP<5>
  VSS67  = GND
  DQ6_A  = M_J_CPU0_SA_DQ<6>
  VSS68  = GND
  DQ7_A  = M_J_CPU0_SA_DQ<7>
  VSS69  = GND
  DQ10_A  = M_J_CPU0_SA_DQ<10>
  VSS70  = GND
  DQ11_A  = M_J_CPU0_SA_DQ<11>
  VSS71  = GND
  \dqs6_a_c||tdqs6_a_c||dqs6_a_t||tdqs6_a_t\  = M_J_CPU0_SA_DQS_DN<6>
  \dqs6_a_t||tdqs6_a_t\  = M_J_CPU0_SA_DQS_DP<6>
  VSS72  = GND
  DQ14_A  = M_J_CPU0_SA_DQ<14>
  VSS73  = GND
  DQ15_A  = M_J_CPU0_SA_DQ<15>
  VSS74  = GND
  DQ18_A  = M_J_CPU0_SA_DQ<18>
  VSS75  = GND
  DQ19_A  = M_J_CPU0_SA_DQ<19>
  VSS76  = GND
  \dqs7_a_c||tdqs7_a_c\  = M_J_CPU0_SA_DQS_DN<7>
  \dqs7_a_t||tdqs7_a_t\  = M_J_CPU0_SA_DQS_DP<7>
  VSS77  = GND
  DQ22_A  = M_J_CPU0_SA_DQ<22>
  VSS78  = GND
  DQ23_A  = M_J_CPU0_SA_DQ<23>
  VSS79  = GND
  DQ26_A  = M_J_CPU0_SA_DQ<26>
  VSS80  = GND
  DQ27_A  = M_J_CPU0_SA_DQ<27>
  VSS81  = GND
  \dqs8_a_c||tdqs8_a_c\  = M_J_CPU0_SA_DQS_DN<8>
  \dqs8_a_t||tdqs8_a_t\  = M_J_CPU0_SA_DQS_DP<8>
  VSS82  = GND
  DQ30_A  = M_J_CPU0_SA_DQ<30>
  VSS83  = GND
  DQ31_A  = M_J_CPU0_SA_DQ<31>
  VSS84  = GND
  CB2_A  = M_J_CPU0_SA_CB<2>
  VSS85  = GND
  CB3_A  = M_J_CPU0_SA_CB<3>
  VSS86  = GND
  \dqs9_a_c||tdqs9_a_c\  = M_J_CPU0_SA_DQS_DN<9>
  \dqs9_a_t||tdqs9_a_t\  = M_J_CPU0_SA_DQS_DP<9>
  VSS87  = GND
  CB6_A  = M_J_CPU0_SA_CB<6>
  VSS88  = GND
  CB7_A  = M_J_CPU0_SA_CB<7>
  VSS89  = GND
  RESET_N  = M_J_CPU0_RESET_N
  VSS90  = GND
  CS1_A_N  = M_J_CPU0_SA_CS_N<1>
  VSS91  = GND
  CA1_A  = M_J_CPU0_SA_CA<1>
  VSS92  = GND
  CA3_A  = M_J_CPU0_SA_CA<3>
  VSS93  = GND
  CA5_A  = M_J_CPU0_SA_CA<5>
  VSS94  = GND
  CK_T  = M_J_CPU0_CLK_DP<0>
  CK_C  = M_J_CPU0_CLK_DN<0>
  VSS95  = GND
  RFU4  = NC
  CA1_B  = M_J_CPU0_SB_CA<1>
  VSS96  = GND
  CA3_B  = M_J_CPU0_SB_CA<3>
  VSS97  = GND
  CA5_B  = M_J_CPU0_SB_CA<5>
  VSS98  = GND
  PAR_B  = M_J_CPU0_SB_PAR
  VSS99  = GND
  CS1_B_N  = M_J_CPU0_SB_CS_N<1>
  VSS100  = GND
  RFU5  = NC
  RFU6  = NC
  VSS101  = GND
  CB6_B  = M_J_CPU0_SB_CB<6>
  VSS102  = GND
  CB7_B  = M_J_CPU0_SB_CB<7>
  VSS103  = GND
  DQS4_B_C  = M_J_CPU0_SB_DQS_DN<4>
  DQS4_B_T  = M_J_CPU0_SB_DQS_DP<4>
  VSS104  = GND
  CB2_B  = M_J_CPU0_SB_CB<2>
  VSS105  = GND
  CB3_B  = M_J_CPU0_SB_CB<3>
  VSS106  = GND
  DQ2_B  = M_J_CPU0_SB_DQ<2>
  VSS107  = GND
  DQ3_B  = M_J_CPU0_SB_DQ<3>
  VSS108  = GND
  \dqs5_b_c||tdqs5_b_c\  = M_J_CPU0_SB_DQS_DN<5>
  \dqs5_b_t||tdqs5_b_t\  = M_J_CPU0_SB_DQS_DP<5>
  VSS109  = GND
  DQ6_B  = M_J_CPU0_SB_DQ<6>
  VSS110  = GND
  DQ7_B  = M_J_CPU0_SB_DQ<7>
  VSS111  = GND
  DQ10_B  = M_J_CPU0_SB_DQ<10>
  VSS112  = GND
  DQ11_B  = M_J_CPU0_SB_DQ<11>
  VSS113  = GND
  \dqs6_b_c||tdqs6_b_c\  = M_J_CPU0_SB_DQS_DN<6>
  \dqs6_b_t||tdqs6_b_t\  = M_J_CPU0_SB_DQS_DP<6>
  VSS114  = GND
  DQ14_B  = M_J_CPU0_SB_DQ<14>
  VSS115  = GND
  DQ15_B  = M_J_CPU0_SB_DQ<15>
  VSS116  = GND
  DQ18_B  = M_J_CPU0_SB_DQ<18>
  VSS117  = GND
  DQ19_B  = M_J_CPU0_SB_DQ<19>
  VSS118  = GND
  \dqs7_b_c||tdqs7_b_c\  = M_J_CPU0_SB_DQS_DN<7>
  \dqs7_b_t||tdqs7_b_t\  = M_J_CPU0_SB_DQS_DP<7>
  VSS119  = GND
  DQ22_B  = M_J_CPU0_SB_DQ<22>
  VSS120  = GND
  DQ23_B  = M_J_CPU0_SB_DQ<23>
  VSS121  = GND
  DQ26_B  = M_J_CPU0_SB_DQ<26>
  VSS122  = GND
  DQ27_B  = M_J_CPU0_SB_DQ<27>
  VSS123  = GND
  \dqs8_b_c||tdqs8_b_c\  = M_J_CPU0_SB_DQS_DN<8>
  \dqs8_b_t||tdqs8_b_t\  = M_J_CPU0_SB_DQS_DP<8>
  VSS124  = GND
  DQ30_B  = M_J_CPU0_SB_DQ<30>
  VSS125  = GND
  DQ31_B  = M_J_CPU0_SB_DQ<31>
  VSS126  = GND
  G1  = GND
  G2  = GND
  G3  = GND

(kicad_pcb
	(version 20260206)
	(generator "pcbnew")
	(generator_version "10.0")
	(general
		(thickness 1.6)
		(legacy_teardrops no)
	)
	(paper "A4")
	(title_block
		(title "04192023_DAF0TMB3IC0_F0TG_MB_C_brd_V02_OCP.brd")
		(comment 1 "Grand Teton / footprint 802 of 8354 (J68), pads 184-229 of 291")
	)
	(layers
		(0 "F.Cu" signal "TOP")
		(4 "In1.Cu" signal "GND")
		(6 "In2.Cu" signal "IN1")
		(8 "In3.Cu" signal "GND1")
		(10 "In4.Cu" signal "IN2")
		(12 "In5.Cu" signal "GND2")
		(14 "In6.Cu" signal "IN3")
		(16 "In7.Cu" signal "GND3")
		(18 "In8.Cu" signal "VCC")
		(20 "In9.Cu" signal "VCC1")
		(22 "In10.Cu" signal "GND4")
		(24 "In11.Cu" signal "IN4")
		(26 "In12.Cu" signal "GND5")
		(28 "In13.Cu" signal "IN5")
		(30 "In14.Cu" signal "GND6")
		(32 "In15.Cu" signal "IN6")
		(34 "In16.Cu" signal "GND7")
		(2 "B.Cu" signal "BOTTOM")
		(9 "F.Adhes" user "F.Adhesive")
		(11 "B.Adhes" user "B.Adhesive")
		(13 "F.Paste" user "Package Geometry/Pastemask Top")
		(15 "B.Paste" user "Package Geometry/Pastemask Bottom")
		(5 "F.SilkS" user "Ref Des/Silkscreen Top")
		(7 "B.SilkS" user "Ref Des/Silkscreen Bottom")
		(1 "F.Mask" user "Board Geometry/Soldermask Top")
		(3 "B.Mask" user "Board Geometry/Soldermask Bottom")
		(17 "Dwgs.User" user "User.Drawings")
		(19 "Cmts.User" user "User.Comments")
		(21 "Eco1.User" user "User.Eco1")
		(23 "Eco2.User" user "User.Eco2")
		(25 "Edge.Cuts" user "Board Geometry/Outline")
		(27 "Margin" user)
		(31 "F.CrtYd" user "Package Geometry/Place Bound Top")
		(29 "B.CrtYd" user "Package Geometry/Place Bound Bottom")
		(35 "F.Fab" user "Ref Des/Assembly Top")
		(33 "B.Fab" user "Ref Des/Assembly Bottom")
	)
	(footprint ""
		(layer "F.Cu")
		(at 437.05018 -255.560068 180)
		(property "Reference" "J68"
			(at 1.32334 -81.844388 0)
			(unlocked yes)
			(layer "F.SilkS")
			(effects
				(font
					(size 0.7874 0.5842)
					(thickness 0.1524)
				)
			)
		)
		(property "Value" ""
			(at 0 0 180)
			(layer "F.Fab")
			(effects
				(font
					(size 1.27 1.27)
				)
			)
		)
		(duplicate_pad_numbers_are_jumpers no)
		(pad "184" smd rect
			(at 2.050034 -30.174946 90)
			(size 0.519938 1.4986)
			(layers "F.Cu" "F.Mask" "F.Paste")
			(net "GND")
		)
		(pad "185" smd rect
			(at 2.050034 -29.325062 90)
			(size 0.519938 1.4986)
			(layers "F.Cu" "F.Mask" "F.Paste")
			(net "M_J_CPU0_SA_DQ<26>")
		)
		(pad "186" smd rect
			(at 2.050034 -28.474924 90)
			(size 0.519938 1.4986)
			(layers "F.Cu" "F.Mask" "F.Paste")
			(net "GND")
		)
		(pad "187" smd rect
			(at 2.050034 -27.62504 90)
			(size 0.519938 1.4986)
			(layers "F.Cu" "F.Mask" "F.Paste")
			(net "M_J_CPU0_SA_DQ<27>")
		)
		(pad "188" smd rect
			(at 2.050034 -26.774902 90)
			(size 0.519938 1.4986)
			(layers "F.Cu" "F.Mask" "F.Paste")
			(net "GND")
		)
		(pad "189" smd rect
			(at 2.050034 -25.925018 90)
			(size 0.519938 1.4986)
			(layers "F.Cu" "F.Mask" "F.Paste")
			(net "M_J_CPU0_SA_DQS_DN<8>")
		)
		(pad "190" smd rect
			(at 2.050034 -25.07488 90)
			(size 0.519938 1.4986)
			(layers "F.Cu" "F.Mask" "F.Paste")
			(net "M_J_CPU0_SA_DQS_DP<8>")
		)
		(pad "191" smd rect
			(at 2.050034 -24.224996 90)
			(size 0.519938 1.4986)
			(layers "F.Cu" "F.Mask" "F.Paste")
			(net "GND")
		)
		(pad "192" smd rect
			(at 2.050034 -23.375112 90)
			(size 0.519938 1.4986)
			(layers "F.Cu" "F.Mask" "F.Paste")
			(net "M_J_CPU0_SA_DQ<30>")
		)
		(pad "193" smd rect
			(at 2.050034 -22.524974 90)
			(size 0.519938 1.4986)
			(layers "F.Cu" "F.Mask" "F.Paste")
			(net "GND")
		)
		(pad "194" smd rect
			(at 2.050034 -21.67509 90)
			(size 0.519938 1.4986)
			(layers "F.Cu" "F.Mask" "F.Paste")
			(net "M_J_CPU0_SA_DQ<31>")
		)
		(pad "195" smd rect
			(at 2.050034 -20.824952 90)
			(size 0.519938 1.4986)
			(layers "F.Cu" "F.Mask" "F.Paste")
			(net "GND")
		)
		(pad "196" smd rect
			(at 2.050034 -19.975068 90)
			(size 0.519938 1.4986)
			(layers "F.Cu" "F.Mask" "F.Paste")
			(net "M_J_CPU0_SA_CB<2>")
		)
		(pad "197" smd rect
			(at 2.050034 -19.12493 90)
			(size 0.519938 1.4986)
			(layers "F.Cu" "F.Mask" "F.Paste")
			(net "GND")
		)
		(pad "198" smd rect
			(at 2.050034 -18.275046 90)
			(size 0.519938 1.4986)
			(layers "F.Cu" "F.Mask" "F.Paste")
			(net "M_J_CPU0_SA_CB<3>")
		)
		(pad "199" smd rect
			(at 2.050034 -17.424908 90)
			(size 0.519938 1.4986)
			(layers "F.Cu" "F.Mask" "F.Paste")
			(net "GND")
		)
		(pad "200" smd rect
			(at 2.050034 -16.575024 90)
			(size 0.519938 1.4986)
			(layers "F.Cu" "F.Mask" "F.Paste")
			(net "M_J_CPU0_SA_DQS_DN<9>")
		)
		(pad "201" smd rect
			(at 2.050034 -15.724886 90)
			(size 0.519938 1.4986)
			(layers "F.Cu" "F.Mask" "F.Paste")
			(net "M_J_CPU0_SA_DQS_DP<9>")
		)
		(pad "202" smd rect
			(at 2.050034 -14.875002 90)
			(size 0.519938 1.4986)
			(layers "F.Cu" "F.Mask" "F.Paste")
			(net "GND")
		)
		(pad "203" smd rect
			(at 2.050034 -14.025118 90)
			(size 0.519938 1.4986)
			(layers "F.Cu" "F.Mask" "F.Paste")
			(net "M_J_CPU0_SA_CB<6>")
		)
		(pad "204" smd rect
			(at 2.050034 -13.17498 90)
			(size 0.519938 1.4986)
			(layers "F.Cu" "F.Mask" "F.Paste")
			(net "GND")
		)
		(pad "205" smd rect
			(at 2.050034 -12.325096 90)
			(size 0.519938 1.4986)
			(layers "F.Cu" "F.Mask" "F.Paste")
			(net "M_J_CPU0_SA_CB<7>")
		)
		(pad "206" smd rect
			(at 2.050034 -11.474958 90)
			(size 0.519938 1.4986)
			(layers "F.Cu" "F.Mask" "F.Paste")
			(net "GND")
		)
		(pad "207" smd rect
			(at 2.050034 -10.625074 90)
			(size 0.519938 1.4986)
			(layers "F.Cu" "F.Mask" "F.Paste")
			(net "M_J_CPU0_RESET_N")
		)
		(pad "208" smd rect
			(at 2.050034 -9.774936 90)
			(size 0.519938 1.4986)
			(layers "F.Cu" "F.Mask" "F.Paste")
			(net "GND")
		)
		(pad "209" smd rect
			(at 2.050034 -8.925052 90)
			(size 0.519938 1.4986)
			(layers "F.Cu" "F.Mask" "F.Paste")
			(net "M_J_CPU0_SA_CS_N<1>")
		)
		(pad "210" smd rect
			(at 2.050034 -8.074914 90)
			(size 0.519938 1.4986)
			(layers "F.Cu" "F.Mask" "F.Paste")
			(net "GND")
		)
		(pad "211" smd rect
			(at 2.050034 -7.22503 90)
			(size 0.519938 1.4986)
			(layers "F.Cu" "F.Mask" "F.Paste")
			(net "M_J_CPU0_SA_CA<1>")
		)
		(pad "212" smd rect
			(at 2.050034 -6.374892 90)
			(size 0.519938 1.4986)
			(layers "F.Cu" "F.Mask" "F.Paste")
			(net "GND")
		)
		(pad "213" smd rect
			(at 2.050034 -5.525008 90)
			(size 0.519938 1.4986)
			(layers "F.Cu" "F.Mask" "F.Paste")
			(net "M_J_CPU0_SA_CA<3>")
		)
		(pad "214" smd rect
			(at 2.050034 -4.675124 90)
			(size 0.519938 1.4986)
			(layers "F.Cu" "F.Mask" "F.Paste")
			(net "GND")
		)
		(pad "215" smd rect
			(at 2.050034 -3.824986 90)
			(size 0.519938 1.4986)
			(layers "F.Cu" "F.Mask" "F.Paste")
			(net "M_J_CPU0_SA_CA<5>")
		)
		(pad "216" smd rect
			(at 2.050034 -2.975102 90)
			(size 0.519938 1.4986)
			(layers "F.Cu" "F.Mask" "F.Paste")
			(net "GND")
		)
		(pad "217" smd rect
			(at 2.050034 -2.124964 90)
			(size 0.519938 1.4986)
			(layers "F.Cu" "F.Mask" "F.Paste")
			(net "M_J_CPU0_CLK_DP<0>")
		)
		(pad "218" smd rect
			(at 2.050034 -1.27508 90)
			(size 0.519938 1.4986)
			(layers "F.Cu" "F.Mask" "F.Paste")
			(net "M_J_CPU0_CLK_DN<0>")
		)
		(pad "219" smd rect
			(at 2.050034 -0.424942 90)
			(size 0.519938 1.4986)
			(layers "F.Cu" "F.Mask" "F.Paste")
			(net "GND")
		)
		(pad "220" smd rect
			(at 2.050034 5.525008 90)
			(size 0.519938 1.4986)
			(layers "F.Cu" "F.Mask" "F.Paste")
			(net "Net_2379")
		)
		(pad "221" smd rect
			(at 2.050034 6.374892 90)
			(size 0.519938 1.4986)
			(layers "F.Cu" "F.Mask" "F.Paste")
			(net "M_J_CPU0_SB_CA<1>")
		)
		(pad "222" smd rect
			(at 2.050034 7.22503 90)
			(size 0.519938 1.4986)
			(layers "F.Cu" "F.Mask" "F.Paste")
			(net "GND")
		)
		(pad "223" smd rect
			(at 2.050034 8.074914 90)
			(size 0.519938 1.4986)
			(layers "F.Cu" "F.Mask" "F.Paste")
			(net "M_J_CPU0_SB_CA<3>")
		)
		(pad "224" smd rect
			(at 2.050034 8.925052 90)
			(size 0.519938 1.4986)
			(layers "F.Cu" "F.Mask" "F.Paste")
			(net "GND")
		)
		(pad "225" smd rect
			(at 2.050034 9.774936 90)
			(size 0.519938 1.4986)
			(layers "F.Cu" "F.Mask" "F.Paste")
			(net "M_J_CPU0_SB_CA<5>")
		)
		(pad "226" smd rect
			(at 2.050034 10.625074 90)
			(size 0.519938 1.4986)
			(layers "F.Cu" "F.Mask" "F.Paste")
			(net "GND")
		)
		(pad "227" smd rect
			(at 2.050034 11.474958 90)
			(size 0.519938 1.4986)
			(layers "F.Cu" "F.Mask" "F.Paste")
			(net "M_J_CPU0_SB_PAR")
		)
		(pad "228" smd rect
			(at 2.050034 12.325096 90)
			(size 0.519938 1.4986)
			(layers "F.Cu" "F.Mask" "F.Paste")
			(net "GND")
		)
		(pad "229" smd rect
			(at 2.050034 13.17498 90)
			(size 0.519938 1.4986)
			(layers "F.Cu" "F.Mask" "F.Paste")
			(net "M_J_CPU0_SB_CS_N<1>")
		)
	)
)
